
INPUT-UNITS     INCHES

WHEEL     1

RECTANGLE         17        24   0.00000  D10
RECTANGLE         24        17   0.00000  D11
RECTANGLE         21        28   0.00000  D12
RECTANGLE         28        21   0.00000  D13
CIRCLE           272            D14
FLASH     TR268X282X40-45      0.00000  D15
CIRCLE           400            D16
LINE             394            D17
OBLONG           394       670   0.00000  D18
OBLONG           670       394   0.00000  D19
CIRCLE           404            D20
LINE             398            D21
OBLONG           398       674   0.00000  D22
OBLONG           674       398   0.00000  D23
CIRCLE           187            D24
FLASH     TR183X197X40-45      0.00000  D25
CIRCLE           315            D26
CIRCLE           237            D27
CIRCLE           319            D28
CIRCLE            26            D29
FLASH     TR_C5-ALL            0.00000  D30
CIRCLE            18            D31
RECTANGLE         10        50   0.00000  D32
RECTANGLE         50        10   0.00000  D33
RECTANGLE         14        54   0.00000  D34
RECTANGLE         54        14   0.00000  D35
RECTANGLE         10        32   0.00000  D36
RECTANGLE         32        10   0.00000  D37
RECTANGLE         14        36   0.00000  D38
RECTANGLE         36        14   0.00000  D39
CIRCLE            30            D40
CIRCLE            20            D41
CIRCLE            24            D42
CIRCLE           125            D43
RECTANGLE         32        34   0.00000  D44
RECTANGLE         34        32   0.00000  D45
RECTANGLE         36        38   0.00000  D46
RECTANGLE         38        36   0.00000  D47
RECTANGLE         15        46   0.00000  D48
RECTANGLE         46        15   0.00000  D49
RECTANGLE         19        50   0.00000  D50
RECTANGLE         50        19   0.00000  D51
RECTANGLE         11        28   0.00000  D52
RECTANGLE         28        11   0.00000  D53
RECTANGLE         15        32   0.00000  D54
RECTANGLE         32        15   0.00000  D55
RECTANGLE         11        30   0.00000  D56
RECTANGLE         30        11   0.00000  D57
RECTANGLE         15        34   0.00000  D58
RECTANGLE         34        15   0.00000  D59
RECTANGLE         42        99   0.00000  D60
RECTANGLE         99        42   0.00000  D61
RECTANGLE         46       103   0.00000  D62
RECTANGLE        103        46   0.00000  D63
CIRCLE            61            D64
FLASH     TR57X71X15-45        0.00000  D65
CIRCLE            65            D66
CIRCLE           116            D67
FLASH     TR102X116X25-45      0.00000  D68
CIRCLE            86            D69
CIRCLE           106            D70
RECTANGLE         63       119   0.00000  D71
RECTANGLE        119        63   0.00000  D72
RECTANGLE         67       123   0.00000  D73
RECTANGLE        123        67   0.00000  D74
RECTANGLE        128       138   0.00000  D75
RECTANGLE        138       128   0.00000  D76
RECTANGLE        132       142   0.00000  D77
RECTANGLE        142       132   0.00000  D78
RECTANGLE         67        99   0.00000  D79
RECTANGLE         99        67   0.00000  D80
RECTANGLE         71       103   0.00000  D81
RECTANGLE        103        71   0.00000  D82
RECTANGLE         85        89   0.00000  D83
RECTANGLE         89        85   0.00000  D84
RECTANGLE         89        93   0.00000  D85
RECTANGLE         93        89   0.00000  D86
RECTANGLE         12        79   0.00000  D87
RECTANGLE         79        12   0.00000  D88
RECTANGLE         16        83   0.00000  D89
RECTANGLE         83        16   0.00000  D90
RECTANGLE         12        32   0.00000  D91
RECTANGLE         32        12   0.00000  D92
RECTANGLE         16        36   0.00000  D93
RECTANGLE         36        16   0.00000  D94
RECTANGLE          7        32   0.00000  D95
RECTANGLE         32         7   0.00000  D96
RECTANGLE         11        36   0.00000  D97
RECTANGLE         36        11   0.00000  D98
RECTANGLE         18        20   0.00000  D99
RECTANGLE         20        18   0.00000  D100
RECTANGLE         22        24   0.00000  D101
RECTANGLE         24        22   0.00000  D102
CIRCLE            70            D103
FLASH     TR66X80X15-45        0.00000  D104
CIRCLE            74            D105
SQUARE            70   0.00000            D106
SQUARE            74   0.00000            D107
RECTANGLE         63       138   0.00000  D108
RECTANGLE        138        63   0.00000  D109
RECTANGLE         67       142   0.00000  D110
RECTANGLE        142        67   0.00000  D111
RECTANGLE         24        32   0.00000  D112
RECTANGLE         32        24   0.00000  D113
RECTANGLE         28        36   0.00000  D114
RECTANGLE         36        28   0.00000  D115
RECTANGLE         18        52   0.00000  D116
RECTANGLE         52        18   0.00000  D117
RECTANGLE         22        56   0.00000  D118
RECTANGLE         56        22   0.00000  D119
RECTANGLE         22        32   0.00000  D120
RECTANGLE         32        22   0.00000  D121
RECTANGLE         26        36   0.00000  D122
RECTANGLE         36        26   0.00000  D123
LINE              94            D124
OBLONG            94       143   0.00000  D125
OBLONG           143        94   0.00000  D126
FLASH     B80-129X94-143X15    0.00000  D127
LINE              74            D128
OBLONG            74       123   0.00000  D129
OBLONG           123        74   0.00000  D130
LINE              78            D131
OBLONG            78       127   0.00000  D132
OBLONG           127        78   0.00000  D133
CIRCLE           414            D134
FLASH     TR219X233X40-45      0.00000  D135
CIRCLE           418            D136
RECTANGLE        128       135   0.00000  D137
RECTANGLE        135       128   0.00000  D138
RECTANGLE        132       139   0.00000  D139
RECTANGLE        139       132   0.00000  D140
RECTANGLE         32        36   0.00000  D141
RECTANGLE         36        32   0.00000  D142
RECTANGLE         36        40   0.00000  D143
RECTANGLE         40        36   0.00000  D144
RECTANGLE         22        68   0.00000  D145
RECTANGLE         68        22   0.00000  D146
RECTANGLE         26        72   0.00000  D147
RECTANGLE         72        26   0.00000  D148
RECTANGLE         14        59   0.00000  D149
RECTANGLE         59        14   0.00000  D150
RECTANGLE         18        63   0.00000  D151
RECTANGLE         63        18   0.00000  D152
RECTANGLE         14        56   0.00000  D153
RECTANGLE         56        14   0.00000  D154
RECTANGLE         18        60   0.00000  D155
RECTANGLE         60        18   0.00000  D156
RECTANGLE         40        63   0.00000  D157
RECTANGLE         63        40   0.00000  D158
RECTANGLE         44        67   0.00000  D159
RECTANGLE         67        44   0.00000  D160
RECTANGLE        110       220   0.00000  D161
RECTANGLE        220       110   0.00000  D162
RECTANGLE        114       224   0.00000  D163
RECTANGLE        224       114   0.00000  D164
RECTANGLE         59       134   0.00000  D165
RECTANGLE        134        59   0.00000  D166
LINE              12            D167
OBLONG            12        33   0.00000  D168
OBLONG            33        12   0.00000  D169
LINE              14            D170
OBLONG            14        37   0.00000  D171
OBLONG            37        14   0.00000  D172
RECTANGLE         10        20   0.00000  D173
RECTANGLE         20        10   0.00000  D174
RECTANGLE         14        24   0.00000  D175
RECTANGLE         24        14   0.00000  D176
RECTANGLE        126       270   0.00000  D177
RECTANGLE        270       126   0.00000  D178
RECTANGLE        130       274   0.00000  D179
RECTANGLE        274       130   0.00000  D180
RECTANGLE         44        54   0.00000  D181
RECTANGLE         54        44   0.00000  D182
RECTANGLE         48        58   0.00000  D183
RECTANGLE         58        48   0.00000  D184
RECTANGLE         52       122   0.00000  D185
RECTANGLE        122        52   0.00000  D186
RECTANGLE         56       126   0.00000  D187
RECTANGLE        126        56   0.00000  D188
RECTANGLE         28        32   0.00000  D189
RECTANGLE         32        28   0.00000  D190
RECTANGLE         46        62   0.00000  D191
RECTANGLE         62        46   0.00000  D192
RECTANGLE         50        66   0.00000  D193
RECTANGLE         66        50   0.00000  D194
RECTANGLE         40        50   0.00000  D195
RECTANGLE         50        40   0.00000  D196
CIRCLE            66            D197
FLASH     TR62X76X15-45        0.00000  D198
SQUARE            66   0.00000            D199
CIRCLE         60.15            D200
FLASH     TR_C38-ALL           0.00000  D201
SQUARE         60.15   0.00000            D202
SQUARE         64.15   0.00000            D203
CIRCLE         64.15            D204
CIRCLE           256            D205
FLASH     TR142X156X40-45      0.00000  D206
CIRCLE           260            D207
CIRCLE           115            D208
FLASH     TR101X115X25-45      0.00000  D209
CIRCLE            85            D210
CIRCLE           105            D211
FLASH     TR111X125X25-45      0.00000  D212
CIRCLE            95            D213
CIRCLE            87            D214
FLASH     TR83X97X25-45        0.00000  D215
CIRCLE         49.52            D216
FLASH     TR_C27-ALL           0.00000  D217
CIRCLE         45.52            D218
SQUARE         45.52   0.00000            D219
SQUARE         49.52   0.00000            D220
CIRCLE           113            D221
FLASH     TR99X113X25-45       0.00000  D222
CIRCLE            83            D223
CIRCLE           103            D224
CIRCLE           155            D225
FLASH     TR141X155X40-45      0.00000  D226
CIRCLE           145            D227
CIRCLE           188            D228
FLASH     TR174X188X40-45      0.00000  D229
CIRCLE           158            D230
CIRCLE           178            D231
CIRCLE            42            D232
FLASH     TR_C20-ALL           0.00000  D233
CIRCLE            34            D234
FLASH     TR_C10-ALL           0.00000  D235
LINE             355            D236
OBLONG           355       552   0.00000  D237
OBLONG           552       355   0.00000  D238
LINE             359            D239
OBLONG           359       556   0.00000  D240
OBLONG           556       359   0.00000  D241
RECTANGLE         99       130   0.00000  D242
RECTANGLE        130        99   0.00000  D243
RECTANGLE        103       134   0.00000  D244
RECTANGLE        134       103   0.00000  D245
RECTANGLE         95       130   0.00000  D246
RECTANGLE        130        95   0.00000  D247
RECTANGLE         99       134   0.00000  D248
RECTANGLE        134        99   0.00000  D249
RECTANGLE         24        28   0.00000  D250
RECTANGLE         28        24   0.00000  D251
CIRCLE            39            D252
CIRCLE           118            D253
LINE               6            D254
LINE               2            D255
LINE               1            D256
LINE              70            D257
LINE               4            D258
LINE               8            D259
LINE              10            D260
LINE              25            D261
LINE             5.1            D262
LINE              40            D263
LINE             6.8            D264
LINE              18            D265
LINE               7            D266
LINE              80            D267
LINE              60            D268
LINE             100            D269
LINE              20            D270
LINE              15            D271
LINE              11            D272
LINE              50            D273
LINE              30            D274
LINE              17            D275

